(kicad_pcb
	(version 20260206)
	(generator "pcbnew")
	(generator_version "10.0")
	(general
		(thickness 1.6)
		(legacy_teardrops no)
	)
	(paper "A4")
	(title_block
		(title "Bryce Canyon_R.DPB_16317-1_OCP.brd")
		(comment 1 "Bryce Canyon / footprints 976-983 of 2099")
	)
	(layers
		(0 "F.Cu" signal "TOP")
		(4 "In1.Cu" signal "L2GND")
		(6 "In2.Cu" signal "L3")
		(8 "In3.Cu" signal "L4VCC")
		(10 "In4.Cu" signal "L5VCC")
		(12 "In5.Cu" signal "L6")
		(14 "In6.Cu" signal "L7GND")
		(2 "B.Cu" signal "BOTTOM")
		(9 "F.Adhes" user "F.Adhesive")
		(11 "B.Adhes" user "B.Adhesive")
		(13 "F.Paste" user "Package Geometry/Pastemask Top")
		(15 "B.Paste" user "Package Geometry/Pastemask Bottom")
		(5 "F.SilkS" user "Ref Des/Silkscreen Top")
		(7 "B.SilkS" user "Ref Des/Silkscreen Bottom")
		(1 "F.Mask" user "Board Geometry/Soldermask Top")
		(3 "B.Mask" user "Board Geometry/Soldermask Bottom")
		(17 "Dwgs.User" user "User.Drawings")
		(19 "Cmts.User" user "User.Comments")
		(21 "Eco1.User" user "User.Eco1")
		(23 "Eco2.User" user "User.Eco2")
		(25 "Edge.Cuts" user "Board Geometry/Outline")
		(27 "Margin" user)
		(31 "F.CrtYd" user "Package Geometry/Place Bound Top")
		(29 "B.CrtYd" user "Package Geometry/Place Bound Bottom")
		(35 "F.Fab" user "Ref Des/Assembly Top")
		(33 "B.Fab" user "Ref Des/Assembly Bottom")
	)
	(footprint ""
		(layer "F.Cu")
		(at 83.82 -26.289 180)
		(property "Reference" "Q129"
			(at 0 0 180)
			(layer "F.SilkS")
			(hide yes)
			(effects
				(font
					(size 1.27 1.27)
				)
			)
		)
		(property "Value" "AO4406AL-GP"
			(at -3.707384 -1.5367 180)
			(unlocked yes)
			(layer "F.Fab")
			(hide yes)
			(effects
				(font
					(size 1.016 1.016)
					(thickness 0.1524)
				)
			)
		)
		(property "Device Type" "SOIC8H69"
			(at -3.707384 -3.0607 180)
			(unlocked yes)
			(layer "F.Fab")
			(hide yes)
			(effects
				(font
					(size 1.016 1.016)
					(thickness 0.1524)
				)
			)
		)
		(duplicate_pad_numbers_are_jumpers no)
		(fp_line
			(start 2.1336 1.4224)
			(end 2.1336 -1.4224)
			(stroke
				(width 0.1524)
				(type default)
			)
			(layer "F.SilkS")
		)
		(fp_line
			(start 2.1336 -1.4224)
			(end -2.7432 -1.4224)
			(stroke
				(width 0.1524)
				(type default)
			)
			(layer "F.SilkS")
		)
		(fp_line
			(start -2.1844 -0.0508)
			(end -2.7178 0.508)
			(stroke
				(width 0.1524)
				(type default)
			)
			(layer "F.SilkS")
		)
		(fp_line
			(start -2.6289 3.4417)
			(end -2.6289 1.4732)
			(stroke
				(width 0.381)
				(type default)
			)
			(layer "F.SilkS")
		)
		(fp_line
			(start -2.7178 -0.508)
			(end -2.1844 -0.0508)
			(stroke
				(width 0.1524)
				(type default)
			)
			(layer "F.SilkS")
		)
		(fp_line
			(start -2.7432 1.4224)
			(end 2.1336 1.4224)
			(stroke
				(width 0.1524)
				(type default)
			)
			(layer "F.SilkS")
		)
		(fp_line
			(start -2.7432 1.4224)
			(end -2.6416 1.4224)
			(stroke
				(width 0.1524)
				(type default)
			)
			(layer "F.SilkS")
		)
		(fp_line
			(start -2.7432 -1.4224)
			(end -2.7432 1.4224)
			(stroke
				(width 0.1524)
				(type default)
			)
			(layer "F.SilkS")
		)
		(fp_poly
			(pts
				(xy -2.2098 -1.4224) (xy -2.2098 1.4224) (xy 2.2098 1.4224) (xy 2.2098 -1.4224)
			)
			(stroke
				(width 0)
				(type default)
			)
			(fill yes)
			(layer "F.SilkS")
		)
		(fp_rect
			(start -2.450084 2.999994)
			(end 2.450084 -2.999994)
			(stroke
				(width 0)
				(type default)
			)
			(fill no)
			(layer "F.CrtYd")
		)
		(fp_poly
			(pts
				(xy -2.8194 3.6322) (xy -2.8194 -3.6322) (xy 2.8194 -3.6322) (xy 2.8194 1.18364) (xy 2.450084 1.18364)
				(xy 2.450084 -2.999994) (xy -2.450084 -2.999994) (xy -2.450084 2.999994) (xy 2.450084 2.999994)
				(xy 2.450084 1.18618) (xy 2.8194 1.18618) (xy 2.8194 3.6322)
			)
			(stroke
				(width 0)
				(type default)
			)
			(fill no)
			(layer "F.CrtYd")
		)
		(fp_rect
			(start -2.8194 3.6322)
			(end 2.8194 -3.6322)
			(stroke
				(width 0)
				(type default)
			)
			(fill no)
			(layer "F.Fab")
		)
		(pad "1" smd rect
			(at -1.905 2.54 180)
			(size 0.635 1.651)
			(layers "F.Cu" "F.Mask" "F.Paste")
			(net "P5V_HDD26")
		)
		(pad "2" smd rect
			(at -0.635 2.54 180)
			(size 0.635 1.651)
			(layers "F.Cu" "F.Mask" "F.Paste")
			(net "P5V_HDD26")
		)
		(pad "3" smd rect
			(at 0.635 2.54 180)
			(size 0.635 1.651)
			(layers "F.Cu" "F.Mask" "F.Paste")
			(net "P5V_HDD26")
		)
		(pad "4" smd rect
			(at 1.905 2.54 180)
			(size 0.635 1.651)
			(layers "F.Cu" "F.Mask" "F.Paste")
			(net "SW_HDD_P26")
		)
		(pad "5" smd rect
			(at 1.905 -2.54 180)
			(size 0.635 1.651)
			(layers "F.Cu" "F.Mask" "F.Paste")
			(net "P5V_B_2")
		)
		(pad "6" smd rect
			(at 0.635 -2.54 180)
			(size 0.635 1.651)
			(layers "F.Cu" "F.Mask" "F.Paste")
			(net "P5V_B_2")
		)
		(pad "7" smd rect
			(at -0.635 -2.54 180)
			(size 0.635 1.651)
			(layers "F.Cu" "F.Mask" "F.Paste")
			(net "P5V_B_2")
		)
		(pad "8" smd rect
			(at -1.905 -2.54 180)
			(size 0.635 1.651)
			(layers "F.Cu" "F.Mask" "F.Paste")
			(net "P5V_B_2")
		)
	)
	(footprint ""
		(layer "F.Cu")
		(at 249.7582 -132.1562 180)
		(property "Reference" "R601"
			(at 0 0 180)
			(layer "F.SilkS")
			(hide yes)
			(effects
				(font
					(size 1.27 1.27)
				)
			)
		)
		(property "Value" "2K2R2F-GP"
			(at 0.064008 -3.993896 180)
			(unlocked yes)
			(layer "F.Fab")
			(hide yes)
			(effects
				(font
					(size 1.016 1.016)
					(thickness 0.1524)
				)
			)
		)
		(property "Device Type" "R402H16"
			(at 0.064008 -5.517896 180)
			(unlocked yes)
			(layer "F.Fab")
			(hide yes)
			(effects
				(font
					(size 1.016 1.016)
					(thickness 0.1524)
				)
			)
		)
		(duplicate_pad_numbers_are_jumpers no)
		(fp_line
			(start 0.508 -0.9398)
			(end -0.508 -0.9398)
			(stroke
				(width 0.1524)
				(type default)
			)
			(layer "F.SilkS")
		)
		(fp_line
			(start -0.508 -0.9398)
			(end -0.508 0.9398)
			(stroke
				(width 0.1524)
				(type default)
			)
			(layer "F.SilkS")
		)
		(fp_rect
			(start -0.508 0.9398)
			(end 0.508 -0.9398)
			(stroke
				(width 0)
				(type default)
			)
			(fill no)
			(layer "F.CrtYd")
		)
		(fp_rect
			(start -0.508 0.9398)
			(end 0.508 -0.9398)
			(stroke
				(width 0)
				(type default)
			)
			(fill no)
			(layer "F.Fab")
		)
		(pad "1" smd custom
			(at 0 -0.4445 180)
			(size 0.1397 0.1397)
			(layers "F.Cu" "F.Mask" "F.Paste")
			(net "P3V3_STBY_B")
			(options
				(clearance outline)
				(anchor circle)
			)
			(primitives
				(gr_poly
					(pts
						(arc
							(start -0.1778 -0.2794)
							(mid -0.249642 -0.249642)
							(end -0.2794 -0.1778)
						)
						(arc
							(start -0.2794 0.1778)
							(mid -0.249642 0.249642)
							(end -0.1778 0.2794)
						)
						(arc
							(start 0.1778 0.2794)
							(mid 0.249642 0.249642)
							(end 0.2794 0.1778)
						)
						(arc
							(start 0.2794 -0.1778)
							(mid 0.249642 -0.249642)
							(end 0.1778 -0.2794)
						)
					)
					(width 0)
					(fill yes)
				)
			)
		)
		(pad "2" smd custom
			(at 0 0.4445 180)
			(size 0.1397 0.1397)
			(layers "F.Cu" "F.Mask" "F.Paste")
			(net "I2C_DPB_B_SDA")
			(options
				(clearance outline)
				(anchor circle)
			)
			(primitives
				(gr_poly
					(pts
						(arc
							(start -0.1778 -0.2794)
							(mid -0.249642 -0.249642)
							(end -0.2794 -0.1778)
						)
						(arc
							(start -0.2794 0.1778)
							(mid -0.249642 0.249642)
							(end -0.1778 0.2794)
						)
						(arc
							(start 0.1778 0.2794)
							(mid 0.249642 0.249642)
							(end 0.2794 0.1778)
						)
						(arc
							(start 0.2794 -0.1778)
							(mid 0.249642 -0.249642)
							(end 0.1778 -0.2794)
						)
					)
					(width 0)
					(fill yes)
				)
			)
		)
	)
	(footprint ""
		(layer "F.Cu")
		(at 273.5834 -330.04125 90)
		(property "Reference" "R91"
			(at 0 0 90)
			(layer "F.SilkS")
			(hide yes)
			(effects
				(font
					(size 1.27 1.27)
				)
			)
		)
		(property "Value" "4K7R2F-GP"
			(at 0.064008 -3.993896 90)
			(unlocked yes)
			(layer "F.Fab")
			(hide yes)
			(effects
				(font
					(size 1.016 1.016)
					(thickness 0.1524)
				)
			)
		)
		(property "Device Type" "R402H16"
			(at 0.064008 -5.517896 90)
			(unlocked yes)
			(layer "F.Fab")
			(hide yes)
			(effects
				(font
					(size 1.016 1.016)
					(thickness 0.1524)
				)
			)
		)
		(duplicate_pad_numbers_are_jumpers no)
		(fp_line
			(start 0.508 -0.9398)
			(end -0.508 -0.9398)
			(stroke
				(width 0.1524)
				(type default)
			)
			(layer "F.SilkS")
		)
		(fp_line
			(start -0.508 -0.9398)
			(end -0.508 0.9398)
			(stroke
				(width 0.1524)
				(type default)
			)
			(layer "F.SilkS")
		)
		(fp_rect
			(start -0.508 0.9398)
			(end 0.508 -0.9398)
			(stroke
				(width 0)
				(type default)
			)
			(fill no)
			(layer "F.CrtYd")
		)
		(fp_rect
			(start -0.508 0.9398)
			(end 0.508 -0.9398)
			(stroke
				(width 0)
				(type default)
			)
			(fill no)
			(layer "F.Fab")
		)
		(pad "1" smd custom
			(at 0 -0.4445 90)
			(size 0.1397 0.1397)
			(layers "F.Cu" "F.Mask" "F.Paste")
			(net "P3V3_IN")
			(options
				(clearance outline)
				(anchor circle)
			)
			(primitives
				(gr_poly
					(pts
						(arc
							(start -0.1778 -0.2794)
							(mid -0.249642 -0.249642)
							(end -0.2794 -0.1778)
						)
						(arc
							(start -0.2794 0.1778)
							(mid -0.249642 0.249642)
							(end -0.1778 0.2794)
						)
						(arc
							(start 0.1778 0.2794)
							(mid 0.249642 0.249642)
							(end 0.2794 0.1778)
						)
						(arc
							(start 0.2794 -0.1778)
							(mid 0.249642 -0.249642)
							(end 0.1778 -0.2794)
						)
					)
					(width 0)
					(fill yes)
				)
			)
		)
		(pad "2" smd custom
			(at 0 0.4445 90)
			(size 0.1397 0.1397)
			(layers "F.Cu" "F.Mask" "F.Paste")
			(net "PWM_OUT_FAN2")
			(options
				(clearance outline)
				(anchor circle)
			)
			(primitives
				(gr_poly
					(pts
						(arc
							(start -0.1778 -0.2794)
							(mid -0.249642 -0.249642)
							(end -0.2794 -0.1778)
						)
						(arc
							(start -0.2794 0.1778)
							(mid -0.249642 0.249642)
							(end -0.1778 0.2794)
						)
						(arc
							(start 0.1778 0.2794)
							(mid 0.249642 0.249642)
							(end 0.2794 0.1778)
						)
						(arc
							(start 0.2794 -0.1778)
							(mid 0.249642 -0.249642)
							(end 0.1778 -0.2794)
						)
					)
					(width 0)
					(fill yes)
				)
			)
		)
	)
	(footprint ""
		(layer "F.Cu")
		(at 469.773 -136.525 180)
		(property "Reference" "D23"
			(at 0 0 180)
			(layer "F.SilkS")
			(hide yes)
			(effects
				(font
					(size 1.27 1.27)
				)
			)
		)
		(property "Value" "RB551V30-GP"
			(at 0 -6.7818 180)
			(unlocked yes)
			(layer "F.Fab")
			(hide yes)
			(effects
				(font
					(size 1.016 1.016)
					(thickness 0.1524)
				)
			)
		)
		(property "Device Type" "SOD323AKH38"
			(at 0 -8.6868 180)
			(unlocked yes)
			(layer "F.Fab")
			(hide yes)
			(effects
				(font
					(size 1.016 1.016)
					(thickness 0.1524)
				)
			)
		)
		(duplicate_pad_numbers_are_jumpers no)
		(fp_line
			(start 0.889 2.159)
			(end -0.889 2.159)
			(stroke
				(width 0.1524)
				(type default)
			)
			(layer "F.SilkS")
		)
		(fp_line
			(start 0.889 -1.9304)
			(end 0.889 2.159)
			(stroke
				(width 0.1524)
				(type default)
			)
			(layer "F.SilkS")
		)
		(fp_line
			(start 0.762 2.0574)
			(end -0.762 2.0574)
			(stroke
				(width 0.508)
				(type default)
			)
			(layer "F.SilkS")
		)
		(fp_line
			(start -0.889 2.159)
			(end -0.889 -1.9304)
			(stroke
				(width 0.1524)
				(type default)
			)
			(layer "F.SilkS")
		)
		(fp_line
			(start -0.889 -1.9304)
			(end 0.889 -1.9304)
			(stroke
				(width 0.1524)
				(type default)
			)
			(layer "F.SilkS")
		)
		(fp_rect
			(start -1.016 2.3114)
			(end 1.016 -2.0066)
			(stroke
				(width 0)
				(type default)
			)
			(fill no)
			(layer "F.CrtYd")
		)
		(fp_poly
			(pts
				(xy -1.016 -2.0066) (xy 1.016 -2.0066) (xy 1.016 2.3114) (xy -1.016 2.3114)
			)
			(stroke
				(width 0)
				(type default)
			)
			(fill no)
			(layer "F.Fab")
		)
		(pad "A" smd rect
			(at 0 -1.143 180)
			(size 0.5588 1.016)
			(layers "F.Cu" "F.Mask" "F.Paste")
			(net "SW_HDD_R23")
		)
		(pad "K" smd rect
			(at 0 1.143 180)
			(size 0.5588 1.016)
			(layers "F.Cu" "F.Mask" "F.Paste")
			(net "SW_HDD_N23")
		)
	)
	(footprint ""
		(layer "F.Cu")
		(at 18.558002 -230.96855 -90)
		(property "Reference" "R1110"
			(at 0 0 270)
			(layer "F.SilkS")
			(hide yes)
			(effects
				(font
					(size 1.27 1.27)
				)
			)
		)
		(property "Value" "143KR2F-L-1-GP"
			(at 0.064008 -3.993896 270)
			(unlocked yes)
			(layer "F.Fab")
			(hide yes)
			(effects
				(font
					(size 1.016 1.016)
					(thickness 0.1524)
				)
			)
		)
		(property "Device Type" "R402H16"
			(at 0.064008 -5.517896 270)
			(unlocked yes)
			(layer "F.Fab")
			(hide yes)
			(effects
				(font
					(size 1.016 1.016)
					(thickness 0.1524)
				)
			)
		)
		(duplicate_pad_numbers_are_jumpers no)
		(fp_line
			(start -0.508 -0.9398)
			(end -0.508 0.9398)
			(stroke
				(width 0.1524)
				(type default)
			)
			(layer "F.SilkS")
		)
		(fp_line
			(start 0.508 -0.9398)
			(end -0.508 -0.9398)
			(stroke
				(width 0.1524)
				(type default)
			)
			(layer "F.SilkS")
		)
		(fp_rect
			(start -0.508 0.9398)
			(end 0.508 -0.9398)
			(stroke
				(width 0)
				(type default)
			)
			(fill no)
			(layer "F.CrtYd")
		)
		(fp_rect
			(start -0.508 0.9398)
			(end 0.508 -0.9398)
			(stroke
				(width 0)
				(type default)
			)
			(fill no)
			(layer "F.Fab")
		)
		(pad "1" smd custom
			(at 0 -0.4445 270)
			(size 0.1397 0.1397)
			(layers "F.Cu" "F.Mask" "F.Paste")
			(net "AGND_P5V_B_1")
			(options
				(clearance outline)
				(anchor circle)
			)
			(primitives
				(gr_poly
					(pts
						(arc
							(start -0.1778 -0.2794)
							(mid -0.249642 -0.249642)
							(end -0.2794 -0.1778)
						)
						(arc
							(start -0.2794 0.1778)
							(mid -0.249642 0.249642)
							(end -0.1778 0.2794)
						)
						(arc
							(start 0.1778 0.2794)
							(mid 0.249642 0.249642)
							(end 0.2794 0.1778)
						)
						(arc
							(start 0.2794 -0.1778)
							(mid 0.249642 -0.249642)
							(end 0.1778 -0.2794)
						)
					)
					(width 0)
					(fill yes)
				)
			)
		)
		(pad "2" smd custom
			(at 0 0.4445 270)
			(size 0.1397 0.1397)
			(layers "F.Cu" "F.Mask" "F.Paste")
			(net "P5V_B_1_TRIP")
			(options
				(clearance outline)
				(anchor circle)
			)
			(primitives
				(gr_poly
					(pts
						(arc
							(start -0.1778 -0.2794)
							(mid -0.249642 -0.249642)
							(end -0.2794 -0.1778)
						)
						(arc
							(start -0.2794 0.1778)
							(mid -0.249642 0.249642)
							(end -0.1778 0.2794)
						)
						(arc
							(start 0.1778 0.2794)
							(mid 0.249642 0.249642)
							(end 0.2794 0.1778)
						)
						(arc
							(start 0.2794 -0.1778)
							(mid 0.249642 -0.249642)
							(end 0.1778 -0.2794)
						)
					)
					(width 0)
					(fill yes)
				)
			)
		)
	)
	(footprint ""
		(layer "F.Cu")
		(at 41.217596 -360.9594)
		(property "Reference" "R143"
			(at 0 0 0)
			(layer "F.SilkS")
			(hide yes)
			(effects
				(font
					(size 1.27 1.27)
				)
			)
		)
		(property "Value" "10KR2F-2-GP"
			(at 0.064008 -3.993896 0)
			(unlocked yes)
			(layer "F.Fab")
			(hide yes)
			(effects
				(font
					(size 1.016 1.016)
					(thickness 0.1524)
				)
			)
		)
		(property "Device Type" "R402H16"
			(at 0.064008 -5.517896 0)
			(unlocked yes)
			(layer "F.Fab")
			(hide yes)
			(effects
				(font
					(size 1.016 1.016)
					(thickness 0.1524)
				)
			)
		)
		(duplicate_pad_numbers_are_jumpers no)
		(fp_line
			(start -0.508 -0.9398)
			(end -0.508 0.9398)
			(stroke
				(width 0.1524)
				(type default)
			)
			(layer "F.SilkS")
		)
		(fp_line
			(start 0.508 -0.9398)
			(end -0.508 -0.9398)
			(stroke
				(width 0.1524)
				(type default)
			)
			(layer "F.SilkS")
		)
		(fp_rect
			(start -0.508 0.9398)
			(end 0.508 -0.9398)
			(stroke
				(width 0)
				(type default)
			)
			(fill no)
			(layer "F.CrtYd")
		)
		(fp_rect
			(start -0.508 0.9398)
			(end 0.508 -0.9398)
			(stroke
				(width 0)
				(type default)
			)
			(fill no)
			(layer "F.Fab")
		)
		(pad "1" smd custom
			(at 0 -0.4445)
			(size 0.1397 0.1397)
			(layers "F.Cu" "F.Mask" "F.Paste")
			(net "P3V3_IN")
			(options
				(clearance outline)
				(anchor circle)
			)
			(primitives
				(gr_poly
					(pts
						(arc
							(start -0.1778 -0.2794)
							(mid -0.249642 -0.249642)
							(end -0.2794 -0.1778)
						)
						(arc
							(start -0.2794 0.1778)
							(mid -0.249642 0.249642)
							(end -0.1778 0.2794)
						)
						(arc
							(start 0.1778 0.2794)
							(mid 0.249642 0.249642)
							(end 0.2794 0.1778)
						)
						(arc
							(start 0.2794 -0.1778)
							(mid 0.249642 -0.249642)
							(end 0.1778 -0.2794)
						)
					)
					(width 0)
					(fill yes)
				)
			)
		)
		(pad "2" smd custom
			(at 0 0.4445)
			(size 0.1397 0.1397)
			(layers "F.Cu" "F.Mask" "F.Paste")
			(net "FAN_EN")
			(options
				(clearance outline)
				(anchor circle)
			)
			(primitives
				(gr_poly
					(pts
						(arc
							(start -0.1778 -0.2794)
							(mid -0.249642 -0.249642)
							(end -0.2794 -0.1778)
						)
						(arc
							(start -0.2794 0.1778)
							(mid -0.249642 0.249642)
							(end -0.1778 0.2794)
						)
						(arc
							(start 0.1778 0.2794)
							(mid 0.249642 0.249642)
							(end 0.2794 0.1778)
						)
						(arc
							(start 0.2794 -0.1778)
							(mid 0.249642 -0.249642)
							(end 0.1778 -0.2794)
						)
					)
					(width 0)
					(fill yes)
				)
			)
		)
	)
	(footprint ""
		(layer "F.Cu")
		(at 97.863914 -39.705026)
		(property "Reference" "TP151"
			(at 0 0 0)
			(layer "F.SilkS")
			(hide yes)
			(effects
				(font
					(size 1.27 1.27)
				)
			)
		)
		(property "Value" "*"
			(at -0.0508 -1.6764 0)
			(unlocked yes)
			(layer "F.Fab")
			(hide yes)
			(effects
				(font
					(size 1.016 1.016)
					(thickness 0.1524)
				)
			)
		)
		(property "Device Type" "TPAD32"
			(at -0.0508 -3.2004 0)
			(unlocked yes)
			(layer "F.Fab")
			(hide yes)
			(effects
				(font
					(size 1.016 1.016)
					(thickness 0.1524)
				)
			)
		)
		(duplicate_pad_numbers_are_jumpers no)
		(fp_poly
			(pts
				(arc
					(start 0.4064 0)
					(mid -0.4064 0)
					(end 0.4064 0)
				)
			)
			(stroke
				(width 0)
				(type default)
			)
			(fill no)
			(layer "F.CrtYd")
		)
		(fp_poly
			(pts
				(arc
					(start 0.7112 0)
					(mid -0.7112 0)
					(end 0.7112 0)
				)
			)
			(stroke
				(width 0)
				(type default)
			)
			(fill no)
			(layer "F.Fab")
		)
		(pad "1" smd circle
			(at 0 0)
			(size 0.8128 0.8128)
			(layers "F.Cu" "F.Mask" "F.Paste")
			(net "ACT_HDD_26")
		)
	)
	(footprint ""
		(layer "F.Cu")
		(at 259.095494 -215.383618)
		(property "Reference" "TP1"
			(at 0 0 0)
			(layer "F.SilkS")
			(hide yes)
			(effects
				(font
					(size 1.27 1.27)
				)
			)
		)
		(property "Value" "*"
			(at -0.0508 -1.6764 0)
			(unlocked yes)
			(layer "F.Fab")
			(hide yes)
			(effects
				(font
					(size 1.016 1.016)
					(thickness 0.1524)
				)
			)
		)
		(property "Device Type" "TPAD32"
			(at -0.0508 -3.2004 0)
			(unlocked yes)
			(layer "F.Fab")
			(hide yes)
			(effects
				(font
					(size 1.016 1.016)
					(thickness 0.1524)
				)
			)
		)
		(duplicate_pad_numbers_are_jumpers no)
		(fp_poly
			(pts
				(arc
					(start 0.4064 0)
					(mid -0.4064 0)
					(end 0.4064 0)
				)
			)
			(stroke
				(width 0)
				(type default)
			)
			(fill no)
			(layer "F.CrtYd")
		)
		(fp_poly
			(pts
				(arc
					(start 0.7112 0)
					(mid -0.7112 0)
					(end 0.7112 0)
				)
			)
			(stroke
				(width 0)
				(type default)
			)
			(fill no)
			(layer "F.Fab")
		)
		(pad "1" smd circle
			(at 0 0)
			(size 0.8128 0.8128)
			(layers "F.Cu" "F.Mask" "F.Paste")
			(net "VOL_SEN_INT_N")
		)
	)
)
